(kicad_pcb
	(version 20260206)
	(generator "pcbnew")
	(generator_version "10.0")
	(general
		(thickness 1.6)
		(legacy_teardrops no)
	)
	(paper "A4")
	(title_block
		(title "03242023_DA0F0TMBIJ0_F0T_Motherboard_J_brd_V01_OCP.brd")
		(comment 1 "Grand Teton / footprints 893-899 of 6105")
	)
	(layers
		(0 "F.Cu" signal "TOP")
		(4 "In1.Cu" signal "GND")
		(6 "In2.Cu" signal "IN1")
		(8 "In3.Cu" signal "GND1")
		(10 "In4.Cu" signal "IN2")
		(12 "In5.Cu" signal "GND2")
		(14 "In6.Cu" signal "IN3")
		(16 "In7.Cu" signal "GND3")
		(18 "In8.Cu" signal "VCC")
		(20 "In9.Cu" signal "VCC1")
		(22 "In10.Cu" signal "GND4")
		(24 "In11.Cu" signal "IN4")
		(26 "In12.Cu" signal "GND5")
		(28 "In13.Cu" signal "IN5")
		(30 "In14.Cu" signal "GND6")
		(32 "In15.Cu" signal "IN6")
		(34 "In16.Cu" signal "GND7")
		(2 "B.Cu" signal "BOTTOM")
		(9 "F.Adhes" user "F.Adhesive")
		(11 "B.Adhes" user "B.Adhesive")
		(13 "F.Paste" user "Package Geometry/Pastemask Top")
		(15 "B.Paste" user "Package Geometry/Pastemask Bottom")
		(5 "F.SilkS" user "Ref Des/Silkscreen Top")
		(7 "B.SilkS" user "Ref Des/Silkscreen Bottom")
		(1 "F.Mask" user "Board Geometry/Soldermask Top")
		(3 "B.Mask" user "Board Geometry/Soldermask Bottom")
		(17 "Dwgs.User" user "User.Drawings")
		(19 "Cmts.User" user "User.Comments")
		(21 "Eco1.User" user "User.Eco1")
		(23 "Eco2.User" user "User.Eco2")
		(25 "Edge.Cuts" user "Board Geometry/Outline")
		(27 "Margin" user)
		(31 "F.CrtYd" user "Package Geometry/Place Bound Top")
		(29 "B.CrtYd" user "Package Geometry/Place Bound Bottom")
		(35 "F.Fab" user "Ref Des/Assembly Top")
		(33 "B.Fab" user "Ref Des/Assembly Bottom")
	)
	(footprint ""
		(layer "F.Cu")
		(at 459.280768 -398.59077)
		(property "Reference" "H27"
			(at -5.8166 -5.552948 0)
			(unlocked yes)
			(layer "F.SilkS")
			(effects
				(font
					(size 0.7874 0.5842)
					(thickness 0.1524)
				)
				(justify left)
			)
		)
		(property "Value" ""
			(at 0 0 0)
			(layer "F.Fab")
			(effects
				(font
					(size 1.27 1.27)
				)
			)
		)
		(duplicate_pad_numbers_are_jumpers no)
		(fp_circle
			(center 0 0)
			(end 2.4003 0)
			(stroke
				(width 0.1524)
				(type default)
			)
			(fill no)
			(layer "F.SilkS")
		)
		(fp_arc
			(start 5.688076 3.330194)
			(mid -6.590791 -0.091812)
			(end 5.7785 -3.170936)
			(stroke
				(width 0.1524)
				(type default)
			)
			(layer "B.SilkS")
		)
		(fp_circle
			(center 0 0)
			(end 6.5913 0)
			(stroke
				(width 0.1)
				(type default)
			)
			(fill no)
			(layer "B.Fab")
		)
		(fp_circle
			(center 0 0)
			(end 2.4003 0)
			(stroke
				(width 0.1)
				(type default)
			)
			(fill no)
			(layer "F.Fab")
		)
		(pad "" np_thru_hole circle
			(at 0 0)
			(size 3.175 3.175)
			(drill 3.175)
			(layers "*.Cu" "*.Mask")
			(clearance 0.381)
			(thermal_gap 0.381)
		)
		(zone
			(layers "F.Cu" "B.Cu" "In1.Cu" "In2.Cu" "In3.Cu" "In4.Cu" "In5.Cu" "In6.Cu"
				"In7.Cu" "In8.Cu" "In9.Cu" "In10.Cu" "In11.Cu" "In12.Cu" "In13.Cu" "In14.Cu"
				"In15.Cu" "In16.Cu"
			)
			(hatch none 0.5)
			(connect_pads
				(clearance 0)
			)
			(min_thickness 0.25)
			(keepout
				(tracks not_allowed)
				(vias allowed)
				(pads allowed)
				(copperpour not_allowed)
				(footprints allowed)
			)
			(placement
				(enabled no)
				(sheetname "")
			)
			(fill
				(thermal_gap 0.5)
				(thermal_bridge_width 0.5)
				(island_removal_mode 0)
			)
			(polygon
				(pts
					(arc
						(start 461.376268 -398.59077)
						(mid 457.185268 -398.59077)
						(end 461.376268 -398.59077)
					)
				)
			)
		)
	)
	(footprint ""
		(layer "F.Cu")
		(at 187.842652 -424.87977 -90)
		(property "Reference" "R4901"
			(at 0 0 270)
			(layer "F.SilkS")
			(hide yes)
			(effects
				(font
					(size 1.27 1.27)
				)
			)
		)
		(property "Value" ""
			(at 0 0 270)
			(layer "F.Fab")
			(effects
				(font
					(size 1.27 1.27)
				)
			)
		)
		(duplicate_pad_numbers_are_jumpers no)
		(fp_line
			(start -0.7874 0.4064)
			(end -0.7874 -0.4064)
			(stroke
				(width 0.1524)
				(type default)
			)
			(layer "F.SilkS")
		)
		(fp_line
			(start 0.7874 0.4064)
			(end -0.7874 0.4064)
			(stroke
				(width 0.1524)
				(type default)
			)
			(layer "F.SilkS")
		)
		(fp_line
			(start -0.7874 -0.4064)
			(end 0.7874 -0.4064)
			(stroke
				(width 0.1524)
				(type default)
			)
			(layer "F.SilkS")
		)
		(fp_line
			(start 0.7874 -0.4064)
			(end 0.7874 0.4064)
			(stroke
				(width 0.1524)
				(type default)
			)
			(layer "F.SilkS")
		)
		(fp_line
			(start -0.67945 0.3048)
			(end -0.67945 -0.305054)
			(stroke
				(width 0.1)
				(type default)
			)
			(layer "F.Fab")
		)
		(fp_line
			(start -0.12065 0.3048)
			(end -0.67945 0.3048)
			(stroke
				(width 0.1)
				(type default)
			)
			(layer "F.Fab")
		)
		(fp_line
			(start 0.120396 0.3048)
			(end 0.120396 0.2794)
			(stroke
				(width 0.1)
				(type default)
			)
			(layer "F.Fab")
		)
		(fp_line
			(start 0.67945 0.3048)
			(end 0.120396 0.3048)
			(stroke
				(width 0.1)
				(type default)
			)
			(layer "F.Fab")
		)
		(fp_line
			(start -0.12065 0.2794)
			(end -0.12065 0.3048)
			(stroke
				(width 0.1)
				(type default)
			)
			(layer "F.Fab")
		)
		(fp_line
			(start 0.120396 0.2794)
			(end -0.12065 0.2794)
			(stroke
				(width 0.1)
				(type default)
			)
			(layer "F.Fab")
		)
		(fp_line
			(start -0.12065 -0.2794)
			(end 0.12065 -0.2794)
			(stroke
				(width 0.1)
				(type default)
			)
			(layer "F.Fab")
		)
		(fp_line
			(start 0.12065 -0.2794)
			(end 0.12065 -0.3048)
			(stroke
				(width 0.1)
				(type default)
			)
			(layer "F.Fab")
		)
		(fp_line
			(start 0.12065 -0.3048)
			(end 0.67945 -0.3048)
			(stroke
				(width 0.1)
				(type default)
			)
			(layer "F.Fab")
		)
		(fp_line
			(start 0.67945 -0.3048)
			(end 0.67945 0.3048)
			(stroke
				(width 0.1)
				(type default)
			)
			(layer "F.Fab")
		)
		(fp_line
			(start -0.67945 -0.305054)
			(end -0.12065 -0.305054)
			(stroke
				(width 0.1)
				(type default)
			)
			(layer "F.Fab")
		)
		(fp_line
			(start -0.12065 -0.305054)
			(end -0.12065 -0.2794)
			(stroke
				(width 0.1)
				(type default)
			)
			(layer "F.Fab")
		)
		(pad "1" smd circle
			(at -0.40005 0 270)
			(size 0 0)
			(layers "F.Cu" "F.Mask" "F.Paste")
			(net "P12V_PSU_FUSE")
		)
		(pad "2" smd circle
			(at 0.40005 0 270)
			(size 0 0)
			(layers "F.Cu" "F.Mask" "F.Paste")
			(net "HSC_EN")
		)
	)
	(footprint ""
		(layer "F.Cu")
		(at 118.6561 -362.501942 -90)
		(property "Reference" "PU174"
			(at -2.940558 0.323342 0)
			(unlocked yes)
			(layer "F.SilkS")
			(effects
				(font
					(size 0.7874 0.5842)
					(thickness 0.1524)
				)
			)
		)
		(property "Value" ""
			(at 0 0 270)
			(layer "F.Fab")
			(effects
				(font
					(size 1.27 1.27)
				)
			)
		)
		(duplicate_pad_numbers_are_jumpers no)
		(fp_line
			(start -1.949958 1.610106)
			(end -1.949958 -1.610106)
			(stroke
				(width 0.1524)
				(type default)
			)
			(layer "F.SilkS")
		)
		(fp_line
			(start 1.949958 1.610106)
			(end -1.949958 1.610106)
			(stroke
				(width 0.1524)
				(type default)
			)
			(layer "F.SilkS")
		)
		(fp_line
			(start 1.949958 -1.560068)
			(end 1.949958 1.610106)
			(stroke
				(width 0.1524)
				(type default)
			)
			(layer "F.SilkS")
		)
		(fp_line
			(start -1.949958 -1.610106)
			(end 1.949958 -1.610106)
			(stroke
				(width 0.1524)
				(type default)
			)
			(layer "F.SilkS")
		)
		(fp_line
			(start -0.750062 1.560068)
			(end -0.750062 -1.560068)
			(stroke
				(width 0.1)
				(type default)
			)
			(layer "F.Fab")
		)
		(fp_line
			(start 0.750062 1.560068)
			(end -0.750062 1.560068)
			(stroke
				(width 0.1)
				(type default)
			)
			(layer "F.Fab")
		)
		(fp_line
			(start -0.750062 -1.560068)
			(end 0.750062 -1.560068)
			(stroke
				(width 0.1)
				(type default)
			)
			(layer "F.Fab")
		)
		(fp_line
			(start 0.750062 -1.560068)
			(end 0.750062 1.560068)
			(stroke
				(width 0.1)
				(type default)
			)
			(layer "F.Fab")
		)
		(pad "D" smd rect
			(at 1.100074 0 180)
			(size 1.016 1.4224)
			(layers "F.Cu" "F.Mask" "F.Paste")
			(net "FM_HBM_VPP_SEL_CPU1_D")
		)
		(pad "G" smd rect
			(at -1.100074 -0.94996 180)
			(size 1.016 1.4224)
			(layers "F.Cu" "F.Mask" "F.Paste")
			(net "FM_HBM2_HBM3_VPP_SEL")
		)
		(pad "S" smd rect
			(at -1.100074 0.94996 180)
			(size 1.016 1.4224)
			(layers "F.Cu" "F.Mask" "F.Paste")
			(net "SH_PVPP_HBM_CPU1_N")
		)
	)
	(footprint ""
		(layer "F.Cu")
		(at 194.2719 -65.225168 -90)
		(property "Reference" "PC2204"
			(at 0 0 270)
			(layer "F.SilkS")
			(hide yes)
			(effects
				(font
					(size 1.27 1.27)
				)
			)
		)
		(property "Value" ""
			(at 0 0 270)
			(layer "F.Fab")
			(effects
				(font
					(size 1.27 1.27)
				)
			)
		)
		(duplicate_pad_numbers_are_jumpers no)
		(fp_line
			(start -1.524 0.762)
			(end -1.524 -0.762)
			(stroke
				(width 0.1524)
				(type default)
			)
			(layer "F.SilkS")
		)
		(fp_line
			(start 1.524 0.762)
			(end -1.524 0.762)
			(stroke
				(width 0.1524)
				(type default)
			)
			(layer "F.SilkS")
		)
		(fp_line
			(start -1.524 -0.762)
			(end 1.524 -0.762)
			(stroke
				(width 0.1524)
				(type default)
			)
			(layer "F.SilkS")
		)
		(fp_line
			(start 1.524 -0.762)
			(end 1.524 0.762)
			(stroke
				(width 0.1524)
				(type default)
			)
			(layer "F.SilkS")
		)
		(fp_line
			(start -1.1049 0.724916)
			(end 1.1049 0.724916)
			(stroke
				(width 0.1)
				(type default)
			)
			(layer "F.Fab")
		)
		(fp_line
			(start 1.1049 0.724916)
			(end 1.1049 -0.724916)
			(stroke
				(width 0.1)
				(type default)
			)
			(layer "F.Fab")
		)
		(fp_line
			(start -1.1049 -0.724916)
			(end -1.1049 0.724916)
			(stroke
				(width 0.1)
				(type default)
			)
			(layer "F.Fab")
		)
		(fp_line
			(start 1.1049 -0.724916)
			(end -1.1049 -0.724916)
			(stroke
				(width 0.1)
				(type default)
			)
			(layer "F.Fab")
		)
		(pad "1" smd rect
			(at -0.889 0 90)
			(size 1.016 1.27)
			(layers "F.Cu" "F.Mask" "F.Paste")
			(net "P3V3_E1S_0_R")
		)
		(pad "2" smd rect
			(at 0.889 0 90)
			(size 1.016 1.27)
			(layers "F.Cu" "F.Mask" "F.Paste")
			(net "GND")
		)
	)
	(footprint ""
		(layer "F.Cu")
		(at 348.044008 -20.602194)
		(property "Reference" "R1827"
			(at 0 0 0)
			(layer "F.SilkS")
			(hide yes)
			(effects
				(font
					(size 1.27 1.27)
				)
			)
		)
		(property "Value" ""
			(at 0 0 0)
			(layer "F.Fab")
			(effects
				(font
					(size 1.27 1.27)
				)
			)
		)
		(duplicate_pad_numbers_are_jumpers no)
		(fp_line
			(start -0.7874 -0.4064)
			(end 0.7874 -0.4064)
			(stroke
				(width 0.1524)
				(type default)
			)
			(layer "F.SilkS")
		)
		(fp_line
			(start -0.7874 0.4064)
			(end -0.7874 -0.4064)
			(stroke
				(width 0.1524)
				(type default)
			)
			(layer "F.SilkS")
		)
		(fp_line
			(start 0.7874 -0.4064)
			(end 0.7874 0.4064)
			(stroke
				(width 0.1524)
				(type default)
			)
			(layer "F.SilkS")
		)
		(fp_line
			(start 0.7874 0.4064)
			(end -0.7874 0.4064)
			(stroke
				(width 0.1524)
				(type default)
			)
			(layer "F.SilkS")
		)
		(fp_line
			(start -0.67945 -0.305054)
			(end -0.12065 -0.305054)
			(stroke
				(width 0.1)
				(type default)
			)
			(layer "F.Fab")
		)
		(fp_line
			(start -0.67945 0.3048)
			(end -0.67945 -0.305054)
			(stroke
				(width 0.1)
				(type default)
			)
			(layer "F.Fab")
		)
		(fp_line
			(start -0.12065 -0.305054)
			(end -0.12065 -0.2794)
			(stroke
				(width 0.1)
				(type default)
			)
			(layer "F.Fab")
		)
		(fp_line
			(start -0.12065 -0.2794)
			(end 0.12065 -0.2794)
			(stroke
				(width 0.1)
				(type default)
			)
			(layer "F.Fab")
		)
		(fp_line
			(start -0.12065 0.2794)
			(end -0.12065 0.3048)
			(stroke
				(width 0.1)
				(type default)
			)
			(layer "F.Fab")
		)
		(fp_line
			(start -0.12065 0.3048)
			(end -0.67945 0.3048)
			(stroke
				(width 0.1)
				(type default)
			)
			(layer "F.Fab")
		)
		(fp_line
			(start 0.120396 0.2794)
			(end -0.12065 0.2794)
			(stroke
				(width 0.1)
				(type default)
			)
			(layer "F.Fab")
		)
		(fp_line
			(start 0.120396 0.3048)
			(end 0.120396 0.2794)
			(stroke
				(width 0.1)
				(type default)
			)
			(layer "F.Fab")
		)
		(fp_line
			(start 0.12065 -0.3048)
			(end 0.67945 -0.3048)
			(stroke
				(width 0.1)
				(type default)
			)
			(layer "F.Fab")
		)
		(fp_line
			(start 0.12065 -0.2794)
			(end 0.12065 -0.3048)
			(stroke
				(width 0.1)
				(type default)
			)
			(layer "F.Fab")
		)
		(fp_line
			(start 0.67945 -0.3048)
			(end 0.67945 0.3048)
			(stroke
				(width 0.1)
				(type default)
			)
			(layer "F.Fab")
		)
		(fp_line
			(start 0.67945 0.3048)
			(end 0.120396 0.3048)
			(stroke
				(width 0.1)
				(type default)
			)
			(layer "F.Fab")
		)
		(pad "1" smd circle
			(at -0.40005 0)
			(size 0 0)
			(layers "F.Cu" "F.Mask" "F.Paste")
			(net "USB_OC1_REAR_R_N")
		)
		(pad "2" smd circle
			(at 0.40005 0)
			(size 0 0)
			(layers "F.Cu" "F.Mask" "F.Paste")
			(net "USB_OC1_REAR_N")
		)
	)
	(footprint ""
		(layer "F.Cu")
		(at 317.396622 -55.794148)
		(property "Reference" "R1496"
			(at 0 0 0)
			(layer "F.SilkS")
			(hide yes)
			(effects
				(font
					(size 1.27 1.27)
				)
			)
		)
		(property "Value" ""
			(at 0 0 0)
			(layer "F.Fab")
			(effects
				(font
					(size 1.27 1.27)
				)
			)
		)
		(duplicate_pad_numbers_are_jumpers no)
		(fp_line
			(start -0.7874 -0.4064)
			(end 0.7874 -0.4064)
			(stroke
				(width 0.1524)
				(type default)
			)
			(layer "F.SilkS")
		)
		(fp_line
			(start -0.7874 0.4064)
			(end -0.7874 -0.4064)
			(stroke
				(width 0.1524)
				(type default)
			)
			(layer "F.SilkS")
		)
		(fp_line
			(start 0.7874 -0.4064)
			(end 0.7874 0.4064)
			(stroke
				(width 0.1524)
				(type default)
			)
			(layer "F.SilkS")
		)
		(fp_line
			(start 0.7874 0.4064)
			(end -0.7874 0.4064)
			(stroke
				(width 0.1524)
				(type default)
			)
			(layer "F.SilkS")
		)
		(fp_line
			(start -0.67945 -0.305054)
			(end -0.12065 -0.305054)
			(stroke
				(width 0.1)
				(type default)
			)
			(layer "F.Fab")
		)
		(fp_line
			(start -0.67945 0.3048)
			(end -0.67945 -0.305054)
			(stroke
				(width 0.1)
				(type default)
			)
			(layer "F.Fab")
		)
		(fp_line
			(start -0.12065 -0.305054)
			(end -0.12065 -0.2794)
			(stroke
				(width 0.1)
				(type default)
			)
			(layer "F.Fab")
		)
		(fp_line
			(start -0.12065 -0.2794)
			(end 0.12065 -0.2794)
			(stroke
				(width 0.1)
				(type default)
			)
			(layer "F.Fab")
		)
		(fp_line
			(start -0.12065 0.2794)
			(end -0.12065 0.3048)
			(stroke
				(width 0.1)
				(type default)
			)
			(layer "F.Fab")
		)
		(fp_line
			(start -0.12065 0.3048)
			(end -0.67945 0.3048)
			(stroke
				(width 0.1)
				(type default)
			)
			(layer "F.Fab")
		)
		(fp_line
			(start 0.120396 0.2794)
			(end -0.12065 0.2794)
			(stroke
				(width 0.1)
				(type default)
			)
			(layer "F.Fab")
		)
		(fp_line
			(start 0.120396 0.3048)
			(end 0.120396 0.2794)
			(stroke
				(width 0.1)
				(type default)
			)
			(layer "F.Fab")
		)
		(fp_line
			(start 0.12065 -0.3048)
			(end 0.67945 -0.3048)
			(stroke
				(width 0.1)
				(type default)
			)
			(layer "F.Fab")
		)
		(fp_line
			(start 0.12065 -0.2794)
			(end 0.12065 -0.3048)
			(stroke
				(width 0.1)
				(type default)
			)
			(layer "F.Fab")
		)
		(fp_line
			(start 0.67945 -0.3048)
			(end 0.67945 0.3048)
			(stroke
				(width 0.1)
				(type default)
			)
			(layer "F.Fab")
		)
		(fp_line
			(start 0.67945 0.3048)
			(end 0.120396 0.3048)
			(stroke
				(width 0.1)
				(type default)
			)
			(layer "F.Fab")
		)
		(pad "1" smd circle
			(at -0.40005 0)
			(size 0 0)
			(layers "F.Cu" "F.Mask" "F.Paste")
			(net "P3V3_AUX")
		)
		(pad "2" smd circle
			(at 0.40005 0)
			(size 0 0)
			(layers "F.Cu" "F.Mask" "F.Paste")
			(net "FM_PCH_DFXTESTMODE")
		)
	)
	(footprint ""
		(layer "F.Cu")
		(at 431.202592 -118.815104 -90)
		(property "Reference" "PC1196"
			(at 0 0 270)
			(layer "F.SilkS")
			(hide yes)
			(effects
				(font
					(size 1.27 1.27)
				)
			)
		)
		(property "Value" ""
			(at 0 0 270)
			(layer "F.Fab")
			(effects
				(font
					(size 1.27 1.27)
				)
			)
		)
		(duplicate_pad_numbers_are_jumpers no)
		(fp_line
			(start -0.7874 0.4064)
			(end -0.7874 -0.4064)
			(stroke
				(width 0.1524)
				(type default)
			)
			(layer "F.SilkS")
		)
		(fp_line
			(start 0.7874 0.4064)
			(end -0.7874 0.4064)
			(stroke
				(width 0.1524)
				(type default)
			)
			(layer "F.SilkS")
		)
		(fp_line
			(start -0.7874 -0.4064)
			(end 0.7874 -0.4064)
			(stroke
				(width 0.1524)
				(type default)
			)
			(layer "F.SilkS")
		)
		(fp_line
			(start 0.7874 -0.4064)
			(end 0.7874 0.4064)
			(stroke
				(width 0.1524)
				(type default)
			)
			(layer "F.SilkS")
		)
		(fp_line
			(start -0.67945 0.3048)
			(end -0.67945 -0.305054)
			(stroke
				(width 0.1)
				(type default)
			)
			(layer "F.Fab")
		)
		(fp_line
			(start -0.12065 0.3048)
			(end -0.67945 0.3048)
			(stroke
				(width 0.1)
				(type default)
			)
			(layer "F.Fab")
		)
		(fp_line
			(start 0.120396 0.3048)
			(end 0.120396 0.2794)
			(stroke
				(width 0.1)
				(type default)
			)
			(layer "F.Fab")
		)
		(fp_line
			(start 0.67945 0.3048)
			(end 0.120396 0.3048)
			(stroke
				(width 0.1)
				(type default)
			)
			(layer "F.Fab")
		)
		(fp_line
			(start -0.12065 0.2794)
			(end -0.12065 0.3048)
			(stroke
				(width 0.1)
				(type default)
			)
			(layer "F.Fab")
		)
		(fp_line
			(start 0.120396 0.2794)
			(end -0.12065 0.2794)
			(stroke
				(width 0.1)
				(type default)
			)
			(layer "F.Fab")
		)
		(fp_line
			(start -0.12065 -0.2794)
			(end 0.12065 -0.2794)
			(stroke
				(width 0.1)
				(type default)
			)
			(layer "F.Fab")
		)
		(fp_line
			(start 0.12065 -0.2794)
			(end 0.12065 -0.3048)
			(stroke
				(width 0.1)
				(type default)
			)
			(layer "F.Fab")
		)
		(fp_line
			(start 0.12065 -0.3048)
			(end 0.67945 -0.3048)
			(stroke
				(width 0.1)
				(type default)
			)
			(layer "F.Fab")
		)
		(fp_line
			(start 0.67945 -0.3048)
			(end 0.67945 0.3048)
			(stroke
				(width 0.1)
				(type default)
			)
			(layer "F.Fab")
		)
		(fp_line
			(start -0.67945 -0.305054)
			(end -0.12065 -0.305054)
			(stroke
				(width 0.1)
				(type default)
			)
			(layer "F.Fab")
		)
		(fp_line
			(start -0.12065 -0.305054)
			(end -0.12065 -0.2794)
			(stroke
				(width 0.1)
				(type default)
			)
			(layer "F.Fab")
		)
		(pad "1" smd circle
			(at -0.40005 0 270)
			(size 0 0)
			(layers "F.Cu" "F.Mask" "F.Paste")
			(net "PVCCD_HV_CPU0_VREF")
		)
		(pad "2" smd circle
			(at 0.40005 0 270)
			(size 0 0)
			(layers "F.Cu" "F.Mask" "F.Paste")
			(net "GND")
		)
	)
)
